(kicad_pcb
	(version 20260206)
	(generator "pcbnew")
	(generator_version "10.0")
	(general
		(thickness 1.6)
		(legacy_teardrops no)
	)
	(paper "A4")
	(title_block
		(title "03242023_DA0F0TMBIJ0_F0T_Motherboard_J_brd_V01_OCP.brd")
		(comment 1 "Grand Teton / footprints 1936-1941 of 6105")
	)
	(layers
		(0 "F.Cu" signal "TOP")
		(4 "In1.Cu" signal "GND")
		(6 "In2.Cu" signal "IN1")
		(8 "In3.Cu" signal "GND1")
		(10 "In4.Cu" signal "IN2")
		(12 "In5.Cu" signal "GND2")
		(14 "In6.Cu" signal "IN3")
		(16 "In7.Cu" signal "GND3")
		(18 "In8.Cu" signal "VCC")
		(20 "In9.Cu" signal "VCC1")
		(22 "In10.Cu" signal "GND4")
		(24 "In11.Cu" signal "IN4")
		(26 "In12.Cu" signal "GND5")
		(28 "In13.Cu" signal "IN5")
		(30 "In14.Cu" signal "GND6")
		(32 "In15.Cu" signal "IN6")
		(34 "In16.Cu" signal "GND7")
		(2 "B.Cu" signal "BOTTOM")
		(9 "F.Adhes" user "F.Adhesive")
		(11 "B.Adhes" user "B.Adhesive")
		(13 "F.Paste" user "Package Geometry/Pastemask Top")
		(15 "B.Paste" user "Package Geometry/Pastemask Bottom")
		(5 "F.SilkS" user "Ref Des/Silkscreen Top")
		(7 "B.SilkS" user "Ref Des/Silkscreen Bottom")
		(1 "F.Mask" user "Board Geometry/Soldermask Top")
		(3 "B.Mask" user "Board Geometry/Soldermask Bottom")
		(17 "Dwgs.User" user "User.Drawings")
		(19 "Cmts.User" user "User.Comments")
		(21 "Eco1.User" user "User.Eco1")
		(23 "Eco2.User" user "User.Eco2")
		(25 "Edge.Cuts" user "Board Geometry/Outline")
		(27 "Margin" user)
		(31 "F.CrtYd" user "Package Geometry/Place Bound Top")
		(29 "B.CrtYd" user "Package Geometry/Place Bound Bottom")
		(35 "F.Fab" user "Ref Des/Assembly Top")
		(33 "B.Fab" user "Ref Des/Assembly Bottom")
	)
	(footprint ""
		(layer "F.Cu")
		(at 182.781448 -407.462482 90)
		(property "Reference" "R3925"
			(at 0 0 90)
			(layer "F.SilkS")
			(hide yes)
			(effects
				(font
					(size 1.27 1.27)
				)
			)
		)
		(property "Value" ""
			(at 0 0 90)
			(layer "F.Fab")
			(effects
				(font
					(size 1.27 1.27)
				)
			)
		)
		(duplicate_pad_numbers_are_jumpers no)
		(fp_line
			(start 0.7874 -0.4064)
			(end 0.7874 0.4064)
			(stroke
				(width 0.1524)
				(type default)
			)
			(layer "F.SilkS")
		)
		(fp_line
			(start -0.7874 -0.4064)
			(end 0.7874 -0.4064)
			(stroke
				(width 0.1524)
				(type default)
			)
			(layer "F.SilkS")
		)
		(fp_line
			(start 0.7874 0.4064)
			(end -0.7874 0.4064)
			(stroke
				(width 0.1524)
				(type default)
			)
			(layer "F.SilkS")
		)
		(fp_line
			(start -0.7874 0.4064)
			(end -0.7874 -0.4064)
			(stroke
				(width 0.1524)
				(type default)
			)
			(layer "F.SilkS")
		)
		(fp_line
			(start -0.12065 -0.305054)
			(end -0.12065 -0.2794)
			(stroke
				(width 0.1)
				(type default)
			)
			(layer "F.Fab")
		)
		(fp_line
			(start -0.67945 -0.305054)
			(end -0.12065 -0.305054)
			(stroke
				(width 0.1)
				(type default)
			)
			(layer "F.Fab")
		)
		(fp_line
			(start 0.67945 -0.3048)
			(end 0.67945 0.3048)
			(stroke
				(width 0.1)
				(type default)
			)
			(layer "F.Fab")
		)
		(fp_line
			(start 0.12065 -0.3048)
			(end 0.67945 -0.3048)
			(stroke
				(width 0.1)
				(type default)
			)
			(layer "F.Fab")
		)
		(fp_line
			(start 0.12065 -0.2794)
			(end 0.12065 -0.3048)
			(stroke
				(width 0.1)
				(type default)
			)
			(layer "F.Fab")
		)
		(fp_line
			(start -0.12065 -0.2794)
			(end 0.12065 -0.2794)
			(stroke
				(width 0.1)
				(type default)
			)
			(layer "F.Fab")
		)
		(fp_line
			(start 0.120396 0.2794)
			(end -0.12065 0.2794)
			(stroke
				(width 0.1)
				(type default)
			)
			(layer "F.Fab")
		)
		(fp_line
			(start -0.12065 0.2794)
			(end -0.12065 0.3048)
			(stroke
				(width 0.1)
				(type default)
			)
			(layer "F.Fab")
		)
		(fp_line
			(start 0.67945 0.3048)
			(end 0.120396 0.3048)
			(stroke
				(width 0.1)
				(type default)
			)
			(layer "F.Fab")
		)
		(fp_line
			(start 0.120396 0.3048)
			(end 0.120396 0.2794)
			(stroke
				(width 0.1)
				(type default)
			)
			(layer "F.Fab")
		)
		(fp_line
			(start -0.12065 0.3048)
			(end -0.67945 0.3048)
			(stroke
				(width 0.1)
				(type default)
			)
			(layer "F.Fab")
		)
		(fp_line
			(start -0.67945 0.3048)
			(end -0.67945 -0.305054)
			(stroke
				(width 0.1)
				(type default)
			)
			(layer "F.Fab")
		)
		(pad "1" smd circle
			(at -0.40005 0 90)
			(size 0 0)
			(layers "F.Cu" "F.Mask" "F.Paste")
			(net "IRQ_SML1_PMBUS_ALERT")
		)
		(pad "2" smd circle
			(at 0.40005 0 90)
			(size 0 0)
			(layers "F.Cu" "F.Mask" "F.Paste")
			(net "P3V3_AUX")
		)
	)
	(footprint ""
		(layer "F.Cu")
		(at 98.33864 -31.577788)
		(property "Reference" "R3519"
			(at 0 0 0)
			(layer "F.SilkS")
			(hide yes)
			(effects
				(font
					(size 1.27 1.27)
				)
			)
		)
		(property "Value" ""
			(at 0 0 0)
			(layer "F.Fab")
			(effects
				(font
					(size 1.27 1.27)
				)
			)
		)
		(duplicate_pad_numbers_are_jumpers no)
		(fp_line
			(start -0.7874 -0.4064)
			(end 0.7874 -0.4064)
			(stroke
				(width 0.1524)
				(type default)
			)
			(layer "F.SilkS")
		)
		(fp_line
			(start -0.7874 0.4064)
			(end -0.7874 -0.4064)
			(stroke
				(width 0.1524)
				(type default)
			)
			(layer "F.SilkS")
		)
		(fp_line
			(start 0.7874 -0.4064)
			(end 0.7874 0.4064)
			(stroke
				(width 0.1524)
				(type default)
			)
			(layer "F.SilkS")
		)
		(fp_line
			(start 0.7874 0.4064)
			(end -0.7874 0.4064)
			(stroke
				(width 0.1524)
				(type default)
			)
			(layer "F.SilkS")
		)
		(fp_line
			(start -0.67945 -0.305054)
			(end -0.12065 -0.305054)
			(stroke
				(width 0.1)
				(type default)
			)
			(layer "F.Fab")
		)
		(fp_line
			(start -0.67945 0.3048)
			(end -0.67945 -0.305054)
			(stroke
				(width 0.1)
				(type default)
			)
			(layer "F.Fab")
		)
		(fp_line
			(start -0.12065 -0.305054)
			(end -0.12065 -0.2794)
			(stroke
				(width 0.1)
				(type default)
			)
			(layer "F.Fab")
		)
		(fp_line
			(start -0.12065 -0.2794)
			(end 0.12065 -0.2794)
			(stroke
				(width 0.1)
				(type default)
			)
			(layer "F.Fab")
		)
		(fp_line
			(start -0.12065 0.2794)
			(end -0.12065 0.3048)
			(stroke
				(width 0.1)
				(type default)
			)
			(layer "F.Fab")
		)
		(fp_line
			(start -0.12065 0.3048)
			(end -0.67945 0.3048)
			(stroke
				(width 0.1)
				(type default)
			)
			(layer "F.Fab")
		)
		(fp_line
			(start 0.120396 0.2794)
			(end -0.12065 0.2794)
			(stroke
				(width 0.1)
				(type default)
			)
			(layer "F.Fab")
		)
		(fp_line
			(start 0.120396 0.3048)
			(end 0.120396 0.2794)
			(stroke
				(width 0.1)
				(type default)
			)
			(layer "F.Fab")
		)
		(fp_line
			(start 0.12065 -0.3048)
			(end 0.67945 -0.3048)
			(stroke
				(width 0.1)
				(type default)
			)
			(layer "F.Fab")
		)
		(fp_line
			(start 0.12065 -0.2794)
			(end 0.12065 -0.3048)
			(stroke
				(width 0.1)
				(type default)
			)
			(layer "F.Fab")
		)
		(fp_line
			(start 0.67945 -0.3048)
			(end 0.67945 0.3048)
			(stroke
				(width 0.1)
				(type default)
			)
			(layer "F.Fab")
		)
		(fp_line
			(start 0.67945 0.3048)
			(end 0.120396 0.3048)
			(stroke
				(width 0.1)
				(type default)
			)
			(layer "F.Fab")
		)
		(pad "1" smd circle
			(at -0.40005 0)
			(size 0 0)
			(layers "F.Cu" "F.Mask" "F.Paste")
			(net "P3V3_OCP_V3_2")
		)
		(pad "2" smd circle
			(at 0.40005 0)
			(size 0 0)
			(layers "F.Cu" "F.Mask" "F.Paste")
			(net "SMB_OCP_V3_2_3V3AUX_BUF_SCL")
		)
	)
	(footprint ""
		(layer "F.Cu")
		(at 450.060314 -25.10028 -90)
		(property "Reference" "PR3792"
			(at 0 0 270)
			(layer "F.SilkS")
			(hide yes)
			(effects
				(font
					(size 1.27 1.27)
				)
			)
		)
		(property "Value" ""
			(at 0 0 270)
			(layer "F.Fab")
			(effects
				(font
					(size 1.27 1.27)
				)
			)
		)
		(duplicate_pad_numbers_are_jumpers no)
		(fp_line
			(start -0.7874 0.4064)
			(end -0.7874 -0.4064)
			(stroke
				(width 0.1524)
				(type default)
			)
			(layer "F.SilkS")
		)
		(fp_line
			(start 0.7874 0.4064)
			(end -0.7874 0.4064)
			(stroke
				(width 0.1524)
				(type default)
			)
			(layer "F.SilkS")
		)
		(fp_line
			(start -0.7874 -0.4064)
			(end 0.7874 -0.4064)
			(stroke
				(width 0.1524)
				(type default)
			)
			(layer "F.SilkS")
		)
		(fp_line
			(start 0.7874 -0.4064)
			(end 0.7874 0.4064)
			(stroke
				(width 0.1524)
				(type default)
			)
			(layer "F.SilkS")
		)
		(fp_line
			(start -0.67945 0.3048)
			(end -0.67945 -0.305054)
			(stroke
				(width 0.1)
				(type default)
			)
			(layer "F.Fab")
		)
		(fp_line
			(start -0.12065 0.3048)
			(end -0.67945 0.3048)
			(stroke
				(width 0.1)
				(type default)
			)
			(layer "F.Fab")
		)
		(fp_line
			(start 0.120396 0.3048)
			(end 0.120396 0.2794)
			(stroke
				(width 0.1)
				(type default)
			)
			(layer "F.Fab")
		)
		(fp_line
			(start 0.67945 0.3048)
			(end 0.120396 0.3048)
			(stroke
				(width 0.1)
				(type default)
			)
			(layer "F.Fab")
		)
		(fp_line
			(start -0.12065 0.2794)
			(end -0.12065 0.3048)
			(stroke
				(width 0.1)
				(type default)
			)
			(layer "F.Fab")
		)
		(fp_line
			(start 0.120396 0.2794)
			(end -0.12065 0.2794)
			(stroke
				(width 0.1)
				(type default)
			)
			(layer "F.Fab")
		)
		(fp_line
			(start -0.12065 -0.2794)
			(end 0.12065 -0.2794)
			(stroke
				(width 0.1)
				(type default)
			)
			(layer "F.Fab")
		)
		(fp_line
			(start 0.12065 -0.2794)
			(end 0.12065 -0.3048)
			(stroke
				(width 0.1)
				(type default)
			)
			(layer "F.Fab")
		)
		(fp_line
			(start 0.12065 -0.3048)
			(end 0.67945 -0.3048)
			(stroke
				(width 0.1)
				(type default)
			)
			(layer "F.Fab")
		)
		(fp_line
			(start 0.67945 -0.3048)
			(end 0.67945 0.3048)
			(stroke
				(width 0.1)
				(type default)
			)
			(layer "F.Fab")
		)
		(fp_line
			(start -0.67945 -0.305054)
			(end -0.12065 -0.305054)
			(stroke
				(width 0.1)
				(type default)
			)
			(layer "F.Fab")
		)
		(fp_line
			(start -0.12065 -0.305054)
			(end -0.12065 -0.2794)
			(stroke
				(width 0.1)
				(type default)
			)
			(layer "F.Fab")
		)
		(pad "1" smd circle
			(at -0.40005 0 270)
			(size 0 0)
			(layers "F.Cu" "F.Mask" "F.Paste")
			(net "P12V_AUX")
		)
		(pad "2" smd circle
			(at 0.40005 0 270)
			(size 0 0)
			(layers "F.Cu" "F.Mask" "F.Paste")
			(net "P12V_OCP_VCC_1")
		)
	)
	(footprint ""
		(layer "F.Cu")
		(at 364.50143 -240.276888 90)
		(property "Reference" "C1041"
			(at 0 0 90)
			(layer "F.SilkS")
			(hide yes)
			(effects
				(font
					(size 1.27 1.27)
				)
			)
		)
		(property "Value" ""
			(at 0 0 90)
			(layer "F.Fab")
			(effects
				(font
					(size 1.27 1.27)
				)
			)
		)
		(duplicate_pad_numbers_are_jumpers no)
		(fp_line
			(start 0.7874 -0.4064)
			(end 0.7874 0.4064)
			(stroke
				(width 0.1524)
				(type default)
			)
			(layer "F.SilkS")
		)
		(fp_line
			(start -0.7874 -0.4064)
			(end 0.7874 -0.4064)
			(stroke
				(width 0.1524)
				(type default)
			)
			(layer "F.SilkS")
		)
		(fp_line
			(start 0.7874 0.4064)
			(end -0.7874 0.4064)
			(stroke
				(width 0.1524)
				(type default)
			)
			(layer "F.SilkS")
		)
		(fp_line
			(start -0.7874 0.4064)
			(end -0.7874 -0.4064)
			(stroke
				(width 0.1524)
				(type default)
			)
			(layer "F.SilkS")
		)
		(fp_line
			(start -0.12065 -0.305054)
			(end -0.12065 -0.2794)
			(stroke
				(width 0.1)
				(type default)
			)
			(layer "F.Fab")
		)
		(fp_line
			(start -0.67945 -0.305054)
			(end -0.12065 -0.305054)
			(stroke
				(width 0.1)
				(type default)
			)
			(layer "F.Fab")
		)
		(fp_line
			(start 0.67945 -0.3048)
			(end 0.67945 0.3048)
			(stroke
				(width 0.1)
				(type default)
			)
			(layer "F.Fab")
		)
		(fp_line
			(start 0.12065 -0.3048)
			(end 0.67945 -0.3048)
			(stroke
				(width 0.1)
				(type default)
			)
			(layer "F.Fab")
		)
		(fp_line
			(start 0.12065 -0.2794)
			(end 0.12065 -0.3048)
			(stroke
				(width 0.1)
				(type default)
			)
			(layer "F.Fab")
		)
		(fp_line
			(start -0.12065 -0.2794)
			(end 0.12065 -0.2794)
			(stroke
				(width 0.1)
				(type default)
			)
			(layer "F.Fab")
		)
		(fp_line
			(start 0.120396 0.2794)
			(end -0.12065 0.2794)
			(stroke
				(width 0.1)
				(type default)
			)
			(layer "F.Fab")
		)
		(fp_line
			(start -0.12065 0.2794)
			(end -0.12065 0.3048)
			(stroke
				(width 0.1)
				(type default)
			)
			(layer "F.Fab")
		)
		(fp_line
			(start 0.67945 0.3048)
			(end 0.120396 0.3048)
			(stroke
				(width 0.1)
				(type default)
			)
			(layer "F.Fab")
		)
		(fp_line
			(start 0.120396 0.3048)
			(end 0.120396 0.2794)
			(stroke
				(width 0.1)
				(type default)
			)
			(layer "F.Fab")
		)
		(fp_line
			(start -0.12065 0.3048)
			(end -0.67945 0.3048)
			(stroke
				(width 0.1)
				(type default)
			)
			(layer "F.Fab")
		)
		(fp_line
			(start -0.67945 0.3048)
			(end -0.67945 -0.305054)
			(stroke
				(width 0.1)
				(type default)
			)
			(layer "F.Fab")
		)
		(pad "1" smd circle
			(at -0.40005 0 90)
			(size 0 0)
			(layers "F.Cu" "F.Mask" "F.Paste")
			(net "PVCCIN_CPU0")
		)
		(pad "2" smd circle
			(at 0.40005 0 90)
			(size 0 0)
			(layers "F.Cu" "F.Mask" "F.Paste")
			(net "GND")
		)
	)
	(footprint ""
		(layer "F.Cu")
		(at 83.996276 -79.078836)
		(property "Reference" "D73"
			(at -42.90441 34.331402 90)
			(unlocked yes)
			(layer "F.SilkS")
			(effects
				(font
					(size 0.635 0.4064)
					(thickness 0.1524)
				)
				(justify left)
			)
		)
		(property "Value" ""
			(at 0 0 0)
			(layer "F.Fab")
			(effects
				(font
					(size 1.27 1.27)
				)
			)
		)
		(duplicate_pad_numbers_are_jumpers no)
		(fp_line
			(start -0.90678 0.4826)
			(end -0.90678 -0.4699)
			(stroke
				(width 0.1524)
				(type default)
			)
			(layer "F.SilkS")
		)
		(fp_line
			(start -0.89408 -0.4826)
			(end 0.90678 -0.4826)
			(stroke
				(width 0.1524)
				(type default)
			)
			(layer "F.SilkS")
		)
		(fp_line
			(start -0.79248 -0.4826)
			(end 1.03378 -0.4826)
			(stroke
				(width 0.1524)
				(type default)
			)
			(layer "F.SilkS")
		)
		(fp_line
			(start -0.64008 -0.4826)
			(end 1.16078 -0.4826)
			(stroke
				(width 0.1524)
				(type default)
			)
			(layer "F.SilkS")
		)
		(fp_line
			(start 0.90678 -0.4826)
			(end 0.90678 0.4826)
			(stroke
				(width 0.1524)
				(type default)
			)
			(layer "F.SilkS")
		)
		(fp_line
			(start 0.90678 0.4826)
			(end -0.90678 0.4826)
			(stroke
				(width 0.1524)
				(type default)
			)
			(layer "F.SilkS")
		)
		(fp_line
			(start 1.03378 -0.4826)
			(end 1.03378 0.4826)
			(stroke
				(width 0.1524)
				(type default)
			)
			(layer "F.SilkS")
		)
		(fp_line
			(start 1.03378 0.4826)
			(end -0.79248 0.4826)
			(stroke
				(width 0.1524)
				(type default)
			)
			(layer "F.SilkS")
		)
		(fp_line
			(start 1.16078 -0.4826)
			(end 1.16078 0.4826)
			(stroke
				(width 0.1524)
				(type default)
			)
			(layer "F.SilkS")
		)
		(fp_line
			(start 1.16078 0.4826)
			(end -0.64008 0.4826)
			(stroke
				(width 0.1524)
				(type default)
			)
			(layer "F.SilkS")
		)
		(fp_line
			(start -0.499872 -0.249936)
			(end 0.499872 -0.249936)
			(stroke
				(width 0.1)
				(type default)
			)
			(layer "F.Fab")
		)
		(fp_line
			(start -0.499872 0.249936)
			(end -0.499872 -0.249936)
			(stroke
				(width 0.1)
				(type default)
			)
			(layer "F.Fab")
		)
		(fp_line
			(start 0.499872 -0.249936)
			(end 0.499872 0.249936)
			(stroke
				(width 0.1)
				(type default)
			)
			(layer "F.Fab")
		)
		(fp_line
			(start 0.499872 0.249936)
			(end -0.499872 0.249936)
			(stroke
				(width 0.1)
				(type default)
			)
			(layer "F.Fab")
		)
		(pad "A" smd rect
			(at -0.47498 0)
			(size 0.6096 0.7112)
			(layers "F.Cu" "F.Mask" "F.Paste")
			(net "LED_PWRGD_PVCCD_HV_CPU0")
		)
		(pad "C" smd rect
			(at 0.47498 0)
			(size 0.6096 0.7112)
			(layers "F.Cu" "F.Mask" "F.Paste")
			(net "LED_PWRGD_PVCCD_HV_CPU0_D")
		)
	)
	(footprint ""
		(layer "F.Cu")
		(at 46.582584 -107.031282 180)
		(property "Reference" "R2907"
			(at 0 0 180)
			(layer "F.SilkS")
			(hide yes)
			(effects
				(font
					(size 1.27 1.27)
				)
			)
		)
		(property "Value" ""
			(at 0 0 180)
			(layer "F.Fab")
			(effects
				(font
					(size 1.27 1.27)
				)
			)
		)
		(duplicate_pad_numbers_are_jumpers no)
		(fp_line
			(start 0.7874 0.4064)
			(end -0.7874 0.4064)
			(stroke
				(width 0.1524)
				(type default)
			)
			(layer "F.SilkS")
		)
		(fp_line
			(start 0.7874 -0.4064)
			(end 0.7874 0.4064)
			(stroke
				(width 0.1524)
				(type default)
			)
			(layer "F.SilkS")
		)
		(fp_line
			(start -0.7874 0.4064)
			(end -0.7874 -0.4064)
			(stroke
				(width 0.1524)
				(type default)
			)
			(layer "F.SilkS")
		)
		(fp_line
			(start -0.7874 -0.4064)
			(end 0.7874 -0.4064)
			(stroke
				(width 0.1524)
				(type default)
			)
			(layer "F.SilkS")
		)
		(fp_line
			(start 0.67945 0.3048)
			(end 0.120396 0.3048)
			(stroke
				(width 0.1)
				(type default)
			)
			(layer "F.Fab")
		)
		(fp_line
			(start 0.67945 -0.3048)
			(end 0.67945 0.3048)
			(stroke
				(width 0.1)
				(type default)
			)
			(layer "F.Fab")
		)
		(fp_line
			(start 0.12065 -0.2794)
			(end 0.12065 -0.3048)
			(stroke
				(width 0.1)
				(type default)
			)
			(layer "F.Fab")
		)
		(fp_line
			(start 0.12065 -0.3048)
			(end 0.67945 -0.3048)
			(stroke
				(width 0.1)
				(type default)
			)
			(layer "F.Fab")
		)
		(fp_line
			(start 0.120396 0.3048)
			(end 0.120396 0.2794)
			(stroke
				(width 0.1)
				(type default)
			)
			(layer "F.Fab")
		)
		(fp_line
			(start 0.120396 0.2794)
			(end -0.12065 0.2794)
			(stroke
				(width 0.1)
				(type default)
			)
			(layer "F.Fab")
		)
		(fp_line
			(start -0.12065 0.3048)
			(end -0.67945 0.3048)
			(stroke
				(width 0.1)
				(type default)
			)
			(layer "F.Fab")
		)
		(fp_line
			(start -0.12065 0.2794)
			(end -0.12065 0.3048)
			(stroke
				(width 0.1)
				(type default)
			)
			(layer "F.Fab")
		)
		(fp_line
			(start -0.12065 -0.2794)
			(end 0.12065 -0.2794)
			(stroke
				(width 0.1)
				(type default)
			)
			(layer "F.Fab")
		)
		(fp_line
			(start -0.12065 -0.305054)
			(end -0.12065 -0.2794)
			(stroke
				(width 0.1)
				(type default)
			)
			(layer "F.Fab")
		)
		(fp_line
			(start -0.67945 0.3048)
			(end -0.67945 -0.305054)
			(stroke
				(width 0.1)
				(type default)
			)
			(layer "F.Fab")
		)
		(fp_line
			(start -0.67945 -0.305054)
			(end -0.12065 -0.305054)
			(stroke
				(width 0.1)
				(type default)
			)
			(layer "F.Fab")
		)
		(pad "1" smd circle
			(at -0.40005 0 180)
			(size 0 0)
			(layers "F.Cu" "F.Mask" "F.Paste")
			(net "P3V3_AUX")
		)
		(pad "2" smd circle
			(at 0.40005 0 180)
			(size 0 0)
			(layers "F.Cu" "F.Mask" "F.Paste")
			(net "P3V3_AUX_ADC")
		)
	)
)
